%FSTAX23Y23*%
%MOIN*%
%SFA1B1*%

%IPPOS*%
%ADD17C,0.006000*%
%ADD19C,0.008000*%
%ADD21C,0.005000*%
%ADD153C,0.020000*%
%ADD158C,0.061020*%
%ADD160C,0.075000*%
%ADD168R,0.055000X0.055000*%
%ADD171C,0.016000*%
%LNgrandmaster-1*%
%LPD*%
G54D17*
X02083Y01411D02*
X02084Y01412D01*
Y03895*
X02084Y03896*
G54D19*
X02528Y02618D02*
D01*
X02527Y02618*
X02527Y02617*
X02527Y02617*
X02526Y02616*
X02526Y02616*
X02526Y02615*
X02526Y02615*
X02526Y02614*
X02525Y02614*
X02525Y02613*
X02525Y02613*
X02525Y02613*
X02664Y02755D02*
D01*
X02665Y02755*
X02665Y02756*
X02666Y02756*
X02666Y02757*
X02666Y02757*
X02666Y02758*
X02666Y02758*
X02667Y02759*
X02667Y02759*
X02667Y0276*
X02667Y02761*
X02667Y02761*
X02552Y02615D02*
D01*
X02551Y02614*
X02551Y02614*
X02551Y02613*
X0255Y02613*
X0255Y02612*
X0255Y02612*
X0255Y02611*
X0255Y02611*
X02549Y0261*
X02549Y0261*
X02549Y02609*
X02549Y02609*
X02684Y02747D02*
D01*
X02685Y02748*
X02685Y02748*
X02685Y02748*
X02686Y02749*
X02686Y02749*
X02686Y0275*
X02686Y0275*
X02686Y02751*
X02686Y02752*
X02686Y02752*
X02687Y02753*
X02687Y02753*
X02294Y03901D02*
D01*
X02294Y03901*
X02294Y039*
X02294Y039*
X02294Y03899*
X02294Y03899*
X02294Y03898*
X02295Y03898*
X02295Y03897*
X02295Y03897*
X02296Y03896*
X02296Y03896*
X02296Y03896*
X02579Y03609D02*
D01*
X02579Y0361*
X02579Y0361*
X02579Y03611*
X02579Y03612*
X02579Y03612*
X02579Y03613*
X02578Y03613*
X02578Y03614*
X02578Y03614*
X02577Y03614*
X02577Y03615*
X02577Y03615*
X02505Y0262D02*
X02653Y02767D01*
Y02981*
X02462Y03172D02*
X02653Y02981D01*
X02525Y02463D02*
Y02613D01*
X02528Y02618D02*
X02664Y02755D01*
X02667Y02761D02*
Y03155D01*
X02525Y02613D02*
D01*
X02505Y02442D02*
Y0262D01*
X02386Y02769D02*
X02494Y02661D01*
X02386Y02769D02*
Y03019D01*
X02687Y02753D02*
Y03353D01*
X02549Y01755D02*
Y02609D01*
D01*
X02552Y02615D02*
X02684Y02747D01*
X02638Y02667D02*
X02692Y02721D01*
X02579Y03486D02*
Y03609D01*
X02294Y03901D02*
Y04126D01*
X02296Y03896D02*
X02577Y03615D01*
X02579Y03609D02*
Y03609D01*
X05577Y02214D02*
X0558D01*
X05584Y02218*
X05586*
X03492Y02357D02*
Y03296D01*
X03497Y02344D02*
X03499Y02342D01*
X01363Y01786D02*
X01393Y01816D01*
X01363Y00832D02*
Y01786D01*
X0099Y00687D02*
X01217D01*
X01363Y00832*
X03542Y02415D02*
Y03319D01*
Y02415D02*
X03604Y02353D01*
X03509Y03323D02*
X03523Y0331D01*
Y01467D02*
Y0331D01*
Y01467D02*
X03549Y01441D01*
X03653Y03293D02*
X03695Y03251D01*
Y017D02*
X0372Y01675D01*
X03695Y017D02*
Y03251D01*
X03604Y0209D02*
Y02353D01*
X01574Y0242D02*
X01619Y02375D01*
Y02121D02*
Y02375D01*
X01574Y0242D02*
Y03596D01*
X01568Y02067D02*
Y02389D01*
X01549Y02465D02*
D01*
Y02407D02*
Y02465D01*
Y02407D02*
X01568Y02389D01*
X01549Y02465D02*
Y03621D01*
X03197Y01714D02*
Y02969D01*
X03197Y0297*
X03491Y03297D02*
X03492Y03296D01*
X03224Y03229D02*
X0323Y03235D01*
X03224Y01661D02*
Y03229D01*
X03358Y033D02*
Y03448D01*
X03068Y03395D02*
X03072Y03391D01*
X03064Y03399D02*
X03068Y03395D01*
X03072Y02242D02*
Y03391D01*
X02998Y02618D02*
Y02972D01*
X03021Y02995D02*
Y03821D01*
X02998Y02972D02*
X03021Y02995D01*
X02993Y02985D02*
Y03751D01*
X02998Y02618D02*
X03013Y02603D01*
X03014Y03828D02*
X03021Y03821D01*
X02979Y02971D02*
X02993Y02985D01*
X03013Y02314D02*
Y02603D01*
X03014Y03828D02*
Y03831D01*
X03056Y01811D02*
Y02226D01*
X03072Y02242*
X03252Y01661D02*
Y03293D01*
X03263Y03303*
X02527Y03294D02*
X02667Y03155D01*
X02634Y03406D02*
X02687Y03353D01*
X02527Y03294D02*
Y03434D01*
X02385Y03019D02*
X02386Y03019D01*
X02385Y03019D02*
Y03298D01*
X02362Y02688D02*
X02429Y02621D01*
X02527Y03434D02*
X02579Y03486D01*
X02505Y02442D02*
X02519Y02428D01*
Y02227D02*
Y02428D01*
X02638Y0253D02*
Y02667D01*
X02665Y02398D02*
Y02503D01*
X02638Y0253D02*
X02665Y02503D01*
X02645Y02274D02*
Y02379D01*
X02665Y02398*
X02625Y01771D02*
X02626Y0177D01*
X02625Y01771D02*
Y01777D01*
X02624Y01777D02*
X02625Y01777D01*
X02624Y01777D02*
Y02461D01*
X02004Y01336D02*
Y03816D01*
X02028Y01361D02*
X02029Y01362D01*
X02579Y0179D02*
Y02281D01*
X02475Y02291D02*
X02478Y02288D01*
X02446Y02275D02*
X0245Y02279D01*
Y02282*
X02446Y01437D02*
Y02275D01*
X02409Y01967D02*
Y02283D01*
X02362Y03298D02*
X02459Y03396D01*
X02434Y03546D02*
X02459Y03521D01*
Y03396D02*
Y03521D01*
X02253Y03847D02*
X02479Y03622D01*
X02385Y03298D02*
X02479Y03391D01*
Y03622*
X02341Y0343D02*
X02389Y03478D01*
X02341Y02447D02*
Y0343D01*
X02389Y03478D02*
Y03481D01*
X02362Y02688D02*
Y03298D01*
X02341Y02447D02*
X02389Y02398D01*
X02253Y03847D02*
Y04086D01*
X02299Y01916D02*
Y03491D01*
X02254Y03536D02*
X02299Y03491D01*
X02143Y04106D02*
X02146Y04103D01*
X01979Y04106D02*
X02143D01*
X01925Y0416D02*
X01979Y04106D01*
X01925Y0416D02*
D01*
X01836Y04249D02*
X01925Y0416D01*
X01586Y04314D02*
X01625Y04276D01*
X01393Y04314D02*
X01586D01*
X01625Y04276D02*
X01881D01*
X01345Y04175D02*
Y04266D01*
X01393Y04314*
X02205Y032D02*
Y04144D01*
X02143Y04206D02*
X02205Y04144D01*
X01951Y04206D02*
X02143D01*
X01881Y04276D02*
X01951Y04206D01*
X02043Y04257D02*
X02163D01*
X02294Y04126*
X01681Y04249D02*
X01836D01*
X01631Y04046D02*
Y04199D01*
X01681Y04249*
X01478Y03892D02*
X01631Y04046D01*
X05634Y021D02*
Y02236D01*
Y00947D02*
Y021D01*
X04327Y02307D02*
X04534Y021D01*
X05634*
X04039Y02406D02*
X04062Y02428D01*
X01459Y03147D02*
Y03463D01*
X01478Y03482D02*
Y03892D01*
X01459Y03463D02*
X01478Y03482D01*
X02979Y0246D02*
Y02971D01*
X02967Y02447D02*
X02979Y0246D01*
X02274Y01506D02*
Y02286D01*
X02272Y02289D02*
X02274Y02286D01*
X02272Y02289D02*
Y02463D01*
X02252Y02613D02*
X02259Y02621D01*
X03329Y01826D02*
Y01936D01*
X03324Y01941D02*
X03329Y01936D01*
X03439Y0187D02*
Y01874D01*
X03438Y01875D02*
X03439Y01874D01*
X05577Y02214D02*
X05578Y02214D01*
Y02489*
X02694Y02284D02*
X02702Y02292D01*
Y02293*
X02694Y01481D02*
Y02284D01*
X02389Y01948D02*
Y02398D01*
X02384Y01943D02*
X02389Y01948D01*
X02384Y01941D02*
Y01943D01*
X03744Y01711D02*
Y03261D01*
Y01711D02*
X03774Y01681D01*
Y01667D02*
Y01681D01*
X03773Y01666D02*
X03774Y01667D01*
X05578Y0089D02*
X05634Y00947D01*
X0392Y03102D02*
X03939Y03121D01*
X0392Y01685D02*
Y03102D01*
Y01685D02*
X03924Y01681D01*
Y01536D02*
Y01681D01*
X02604Y01734D02*
Y02431D01*
X02259Y02621D02*
Y03261D01*
X03374Y0327D02*
Y03273D01*
X03368Y03264D02*
X03374Y0327D01*
X03368Y0305D02*
Y03264D01*
X04062Y02428D02*
Y02595D01*
X03789Y03235D02*
X03806D01*
X03769Y03215D02*
X03789Y03235D01*
X03769Y01726D02*
Y03215D01*
Y01726D02*
X03803Y01692D01*
Y01691D02*
Y01692D01*
X0138Y04202D02*
X01438Y0426D01*
X0138Y03617D02*
Y04202D01*
Y03617D02*
X0144Y03557D01*
X03622Y02588D02*
Y03486D01*
Y02588D02*
X03623Y02587D01*
X03394Y02011D02*
Y03447D01*
X03509Y03323D02*
Y03766D01*
X03519Y03776*
Y04071*
X03504Y04086D02*
X03519Y04071D01*
X03344Y02996D02*
Y03286D01*
Y02265D02*
Y02996D01*
X03436Y01999D02*
Y03457D01*
Y01999D02*
X03439Y01996D01*
X03492Y02357D02*
X03501Y02348D01*
X03497Y02344D02*
X03501Y02348D01*
X03344Y03286D02*
X03358Y033D01*
X03302Y01977D02*
Y03344D01*
X03298Y01973D02*
X03302Y01977D01*
X03298Y01971D02*
Y01973D01*
X03834Y01481D02*
Y02321D01*
X03799Y02356D02*
X03834Y02321D01*
X0384Y02861D02*
X03854Y02875D01*
X0384Y02368D02*
Y02861D01*
Y02368D02*
X03894Y02314D01*
X03799Y02356D02*
Y03201D01*
X03824Y02361D02*
X03864Y02321D01*
Y01511D02*
Y02321D01*
X03324Y01941D02*
X03394Y02011D01*
X03604Y0209D02*
X03613Y02081D01*
Y01735D02*
Y02081D01*
X03589Y01711D02*
X03613Y01735D01*
X03498Y02341D02*
X03499Y02342D01*
X02478Y00937D02*
Y02288D01*
X02985Y02287D02*
X03013Y02314D01*
X02205Y01299D02*
Y02408D01*
Y01299D02*
X02206Y01298D01*
X02205Y02468D02*
Y032D01*
Y02468D02*
X02225Y02447D01*
Y02429D02*
Y02447D01*
X02205Y02408D02*
X02225Y02429D01*
X02229Y02586D02*
Y03498D01*
X02234Y03503*
Y03506*
X02502Y01316D02*
Y0221D01*
X02519Y02227*
X0292Y01537D02*
Y02428D01*
X02919Y01536D02*
X0292Y01537D01*
X02942Y02286D02*
X02955D01*
X02967Y02298*
Y02447*
X03342Y02263D02*
X03344Y02265D01*
X02643Y01711D02*
X02648Y01716D01*
X02643Y01616D02*
Y01711D01*
X02648Y01716D02*
Y02265D01*
X02645Y02274D02*
X02647Y02272D01*
Y02266D02*
Y02272D01*
Y02266D02*
X02648Y02265D01*
X02665Y01641D02*
X02666Y0164D01*
X02665Y01641D02*
Y02291D01*
X02726Y01599D02*
Y02293D01*
X02719Y01592D02*
X02726Y01599D01*
X02719Y01591D02*
Y01592D01*
X01884Y02071D02*
Y03601D01*
X02029Y01362D02*
Y03836D01*
X02059Y01386D02*
Y03871D01*
X01754Y02126D02*
Y03661D01*
X01549Y03621D02*
D01*
X01719Y01536D02*
X01779Y01596D01*
Y04156*
X02894Y01561D02*
Y02431D01*
X03894Y01566D02*
Y02314D01*
X0372Y01675D02*
X03724D01*
X03438Y01875D02*
X03469Y01906D01*
X03854Y02875D02*
Y03151D01*
X03829Y02873D02*
Y03176D01*
X03824Y02361D02*
Y02868D01*
X03829Y02873*
X03392Y01949D02*
X03439Y01996D01*
X03392Y01871D02*
Y01949D01*
X03469Y01906D02*
Y03456D01*
G54D21*
X02496Y0039D02*
D01*
X02497Y0039*
X02498Y0039*
X02499Y0039*
X025Y0039*
X02501Y00391*
X02502Y00391*
X02503Y00392*
X02504Y00392*
X02505Y00393*
X02506Y00393*
X02507Y00394*
X02507Y00395*
X02508Y00396*
X02509Y00396*
X02509Y00397*
X0251Y00398*
X0251Y00399*
X02511Y004*
X02511Y00401*
X02511Y00402*
X02511Y00403*
X02511Y00404*
X02511Y00405*
X02466Y0073D02*
D01*
X02459Y00722*
X02453Y00715*
X02447Y00707*
X02442Y00698*
X02438Y0069*
X02434Y00681*
X02431Y00671*
X02428Y00662*
X02426Y00652*
X02425Y00643*
X02425Y00633*
X02425Y0063*
Y00436D02*
D01*
X02425Y00433*
X02425Y0043*
X02426Y00427*
X02427Y00423*
X02428Y0042*
X02429Y00417*
X0243Y00414*
X02432Y00412*
X02434Y00409*
X02436Y00406*
X02438Y00404*
X0244Y00402*
X02443Y004*
X02445Y00398*
X02448Y00396*
X02451Y00394*
X02454Y00393*
X02457Y00392*
X0246Y00391*
X02463Y0039*
X02466Y0039*
X0247Y0039*
X02471Y0039*
X02953Y00399D02*
D01*
X02953Y00399*
X02953Y00399*
X02953Y00399*
X02953Y00399*
X02953Y00399*
X02974Y00391D02*
D01*
X02976Y00391*
X02977Y0039*
X02978Y0039*
X02979Y0039*
X02981Y0039*
X02982Y0039*
X02983Y0039*
X02954Y00399D02*
D01*
X02957Y00397*
X02961Y00395*
X02964Y00394*
X02968Y00393*
X02971Y00392*
X02974Y00391*
X02925Y0047D02*
D01*
X02925Y00462*
X02926Y00455*
X02927Y00449*
X02929Y00442*
X02931Y00435*
X02933Y00429*
X02936Y00422*
X0294Y00416*
X02944Y0041*
X02948Y00405*
X02953Y00399*
X02953Y00399*
X02984Y00391D02*
D01*
X02984Y0039*
X02983Y0039*
X02983Y0039*
X02984Y00391D02*
D01*
X02988Y00391*
X02991Y00391*
X02995Y00392*
X02999Y00393*
X03002Y00394*
X03006Y00396*
X03009Y00398*
X03012Y004*
X03015Y00402*
X03018Y00404*
X03019Y00405*
X02953Y00399D02*
D01*
X02954Y00399*
X02954Y00399*
X02954Y00399*
X02954Y00399*
X02954Y00399*
X02974Y00391D02*
D01*
X02974Y00391*
X02974Y00391*
X02974Y00391*
X02979Y00409D02*
D01*
X02979Y00409*
X02979Y00409*
X02979Y00409*
X0298Y00409*
X0298Y00409*
X0298Y00409*
X02966Y00443D02*
D01*
X02966Y00443*
X02965Y00443*
X02965Y00443*
X02964Y00443*
X02964Y00442*
X02963Y00442*
X02963Y00442*
X02962Y00442*
X02962Y00441*
X02961Y00441*
X02961Y00441*
X02961Y0044*
X0296Y0044*
X0296Y0044*
X0296Y00439*
X02959Y00439*
X02959Y00438*
X02959Y00438*
X02959Y00437*
X02959Y00437*
X02959Y00436*
X02959Y00436*
Y00435*
X02959Y00435*
X02959Y00434*
X02959Y00434*
X02959Y00433*
X02959Y00433*
X02975Y00412D02*
D01*
X02976Y00411*
X02977Y00411*
X02977Y0041*
X02978Y0041*
X02979Y00409*
X02966Y00443D02*
D01*
X02967Y00443*
X02967Y00443*
X02968Y00443*
X02968Y00443*
X02969Y00443*
X02969Y00444*
X0297Y00444*
X0297Y00444*
X02971Y00444*
X02971Y00445*
X02971Y00445*
X02972Y00445*
X02972Y00446*
X02972Y00446*
X02973Y00447*
X02973Y00447*
X02973Y00448*
X02973Y00448*
X02974Y00449*
X02974Y00449*
X02974Y0045*
X02974Y0045*
Y00451*
X02974Y00451*
X02974Y00452*
X02974Y00452*
X02973Y00453*
X02973Y00453*
X02973Y00454*
X02973Y00454*
X02972Y00455*
X02972Y00455*
X02972Y00455*
X02971Y00456*
X02971Y00456*
X02971Y00456*
X0297Y00457*
X0297Y00457*
X02969Y00457*
X02969Y00457*
X02968Y00458*
X02968Y00458*
X02967Y00458*
X02967Y00458*
X02966Y00458*
X02945Y00473D02*
D01*
X02944Y00473*
X02944Y00473*
X02943Y00473*
X02943Y00473*
X02942Y00472*
X02942Y00472*
X02941Y00472*
X02941Y00472*
X0294Y00471*
X0294Y00471*
X0294Y00471*
X02939Y0047*
X02939Y0047*
X02939Y0047*
X02938Y00469*
X02938Y00469*
X02938Y00468*
X02938Y00468*
X02937Y00467*
X02937Y00467*
X02937Y00466*
X02937Y00466*
Y00465*
X02937Y00465*
X02937Y00464*
X02937Y00464*
X02938Y00463*
X02938Y00463*
X02938Y00462*
X02938Y00462*
X02939Y00461*
X02939Y00461*
X02939Y0046*
X0294Y0046*
X0294Y0046*
X0294Y00459*
X02941Y00459*
X02941Y00459*
X02942Y00459*
X02942Y00458*
X02943Y00458*
X02943Y00458*
X02944Y00458*
X02944Y00458*
X02945Y00458*
X02955Y00473D02*
D01*
X02955Y00473*
X02956Y00473*
X02956Y00473*
X02957Y00473*
X02957Y00473*
X02958Y00474*
X02958Y00474*
X02959Y00474*
X02959Y00474*
X02959Y00475*
X0296Y00475*
X0296Y00475*
X02961Y00476*
X02961Y00476*
X02961Y00477*
X02961Y00477*
X02962Y00478*
X02962Y00478*
X02962Y00479*
X02962Y00479*
X02962Y0048*
X02962Y0048*
Y00481*
X02962Y00481*
X02962Y00482*
X02962Y00482*
X02962Y00483*
X02962Y00483*
X02961Y00484*
X02961Y00484*
X02961Y00485*
X02961Y00485*
X0296Y00485*
X0296Y00486*
X02959Y00486*
X02959Y00486*
X02959Y00487*
X02958Y00487*
X02958Y00487*
X02957Y00487*
X02957Y00488*
X02956Y00488*
X02956Y00488*
X02955Y00488*
X02955Y00488*
X02938Y00493D02*
D01*
X02938Y00492*
X02938Y00492*
X02938Y00491*
X02938Y00491*
X02939Y00491*
X02939Y0049*
X0294Y0049*
X0294Y00489*
X0294Y00489*
X02941Y00489*
X02941Y00489*
X02942Y00488*
X02942Y00488*
X02943Y00488*
X02943Y00488*
X02944Y00488*
X02944Y00488*
X02945Y00488*
X02847Y00436D02*
D01*
X02847Y00437*
X02846Y00437*
X02846Y00437*
X02845Y00438*
X02845Y00438*
X02844Y00438*
X02844Y00438*
X02843Y00438*
X02843Y00439*
X02842Y00439*
X02842Y00439*
X02841Y00439*
X02841Y00439*
X0284Y00438*
X0284Y00438*
X02839Y00438*
X02839Y00438*
X02838Y00438*
X02838Y00438*
X02837Y00437*
X02837Y00437*
X02837Y00437*
X02836Y00436*
X02851Y00432D02*
D01*
X02851Y00432*
X02852Y00432*
X02852Y00431*
X02853Y00431*
X02853Y00431*
X02854Y00431*
X02854Y00431*
X02855Y0043*
X02855Y0043*
X02856Y0043*
X02856Y0043*
X02857Y0043*
X02857Y0043*
X02858Y0043*
X02858Y0043*
X02859Y00431*
X02859Y00431*
X0286Y00431*
X0286Y00431*
X02861Y00432*
X02861Y00432*
X02861Y00432*
X02862Y00432*
D01*
X02862Y00433*
X02862Y00433*
X02863Y00434*
X02863Y00434*
X02863Y00435*
X02863Y00435*
X02863Y00436*
X02864Y00436*
X02864Y00437*
X02864Y00437*
X02864Y00438*
X02864Y00438*
X02864Y00439*
X02864Y00439*
X02864Y0044*
X02863Y0044*
X02863Y00441*
X02863Y00441*
X02863Y00442*
X02862Y00442*
X02862Y00442*
X02862Y00443*
X02862Y00443*
X02856Y0046D02*
D01*
X02855Y00459*
X02855Y00459*
X02855Y00458*
X02854Y00458*
X02854Y00457*
X02854Y00457*
X02854Y00457*
X02854Y00456*
X02854Y00455*
X02853Y00455*
X02853Y00454*
X02853Y00454*
X02854Y00453*
X02854Y00453*
X02854Y00452*
X02854Y00452*
X02854Y00451*
X02854Y00451*
X02855Y0045*
X02855Y0045*
X02855Y0045*
X02855Y00449*
X02856Y00449*
X02866Y0046D02*
D01*
X02866Y0046*
X02865Y0046*
X02865Y00461*
X02865Y00461*
X02864Y00461*
X02864Y00461*
X02863Y00461*
X02863Y00462*
X02862Y00462*
X02862Y00462*
X02861Y00462*
X02861Y00462*
X0286Y00462*
X0286Y00462*
X02859Y00462*
X02858Y00461*
X02858Y00461*
X02858Y00461*
X02857Y00461*
X02857Y0046*
X02856Y0046*
X02856Y0046*
X02856Y0046*
X02872Y00454D02*
D01*
X02873Y00453*
X02873Y00453*
X02873Y00453*
X02874Y00452*
X02874Y00452*
X02875Y00452*
X02875Y00452*
X02876Y00452*
X02876Y00452*
X02877Y00451*
X02877Y00451*
X02878Y00451*
X02878Y00451*
X02879Y00452*
X02879Y00452*
X0288Y00452*
X0288Y00452*
X02881Y00452*
X02881Y00452*
X02882Y00453*
X02882Y00453*
X02883Y00453*
X02883Y00454*
D01*
X02883Y00454*
X02884Y00454*
X02884Y00455*
X02884Y00455*
X02884Y00456*
X02885Y00456*
X02885Y00457*
X02885Y00457*
X02885Y00458*
X02885Y00458*
X02885Y00459*
X02885Y00459*
X02885Y0046*
X02885Y0046*
X02885Y00461*
X02885Y00461*
X02884Y00462*
X02884Y00462*
X02884Y00463*
X02884Y00463*
X02883Y00464*
X02883Y00464*
X02883Y00464*
X02879Y00479D02*
D01*
X02878Y00478*
X02878Y00478*
X02878Y00478*
X02878Y00477*
X02877Y00477*
X02877Y00476*
X02877Y00476*
X02877Y00475*
X02877Y00475*
X02877Y00474*
X02877Y00474*
X02877Y00473*
X02877Y00473*
X02877Y00472*
X02877Y00472*
X02877Y00471*
X02877Y00471*
X02877Y0047*
X02878Y0047*
X02878Y00469*
X02878Y00469*
X02879Y00468*
X02879Y00468*
X02803Y00407D02*
D01*
X02803Y00406*
X02803Y00404*
X02804Y00403*
X02804Y00401*
X02805Y004*
X02805Y00398*
X02806Y00397*
X02807Y00396*
X02808Y00394*
X02809Y00393*
X02809Y00393*
X02811Y0043D02*
D01*
X0281Y00428*
X02809Y00426*
X02808Y00425*
X02806Y00423*
X02806Y00421*
X02805Y00419*
X02804Y00417*
X02804Y00415*
X02803Y00413*
X02803Y00411*
X02803Y00409*
X02803Y00407*
X0287Y00489D02*
D01*
X02871Y00489*
X02871Y00489*
X02871Y00489*
X02871Y0049*
X02871Y0049*
X02872Y0049*
X02872Y00491*
X02872Y00491*
X02872Y00491*
X02872Y00492*
X02872Y00492*
X02872Y00492*
X02809Y00393D02*
D01*
X0281Y00392*
X02812Y00391*
X02813Y0039*
X02814Y00389*
X02816Y00389*
X02817Y00388*
X02818Y00387*
X0282Y00387*
X02822Y00387*
X02823Y00387*
X02825Y00387*
X02826Y00387*
X02828Y00387*
X02829Y00387*
X02831Y00387*
X02832Y00388*
X02834Y00388*
X02835Y00389*
X02836Y0039*
X02838Y00391*
X02839Y00392*
X0284Y00393*
X02881Y00482D02*
D01*
X02881Y00482*
X02881Y00482*
X02881Y00482*
X02881Y00482*
X02881Y00482*
X02734Y00406D02*
D01*
X02734Y00407*
X02735Y00407*
X02735Y00407D02*
D01*
X02735Y00407*
X02735Y00408*
X02735Y00408*
X02735Y00408*
X02736Y00408*
X02736Y00408*
X0274Y00435D02*
D01*
X0274Y00436*
X0274Y00436*
X0274Y00437*
X0274Y00438*
X0274Y00438*
X02739Y00439*
X02739Y00439*
X02739Y00439*
X02739Y0044*
X02738Y0044*
X02738Y00441*
X02738Y00441*
X02737Y00441*
X02737Y00442*
X02736Y00442*
X02736Y00442*
X02735Y00442*
X02735Y00443*
X02734Y00443*
X02734Y00443*
X02733Y00443*
X02733Y00443*
X02733Y00443*
Y00458D02*
D01*
X02732Y00458*
X02732Y00458*
X02731Y00458*
X0273Y00458*
X0273Y00457*
X0273Y00457*
X02729Y00457*
X02729Y00457*
X02728Y00457*
X02728Y00456*
X02727Y00456*
X02727Y00455*
X02727Y00455*
X02726Y00455*
X02726Y00454*
X02726Y00454*
X02726Y00453*
X02725Y00453*
X02725Y00452*
X02725Y00452*
X02725Y00451*
X02725Y00451*
Y0045*
X02725Y0045*
X02725Y00449*
X02725Y00449*
X02725Y00448*
X02726Y00448*
X02726Y00447*
X02726Y00447*
X02726Y00446*
X02727Y00446*
X02727Y00445*
X02727Y00445*
X02728Y00445*
X02728Y00444*
X02729Y00444*
X02729Y00444*
X0273Y00444*
X0273Y00443*
X0273Y00443*
X02731Y00443*
X02732Y00443*
X02732Y00443*
X02733Y00443*
X02734Y00458D02*
D01*
X02734Y00458*
X02735Y00458*
X02735Y00458*
X02736Y00458*
X02736Y00458*
X02737Y00459*
X02737Y00459*
X02738Y00459*
X02738Y00459*
X02738Y0046*
X02739Y0046*
X02739Y0046*
X02739Y00461*
X0274Y00461*
X0274Y00462*
X0274Y00462*
X02741Y00463*
X02741Y00463*
X02741Y00464*
X02741Y00464*
X02741Y00465*
X02741Y00465*
Y00466*
X02741Y00466*
X02741Y00467*
X02741Y00467*
X02741Y00468*
X02741Y00468*
X0274Y00469*
X0274Y00469*
X0274Y0047*
X02739Y0047*
X02739Y0047*
X02739Y00471*
X02738Y00471*
X02738Y00472*
X02738Y00472*
X02737Y00472*
X02737Y00472*
X02736Y00472*
X02736Y00473*
X02735Y00473*
X02735Y00473*
X02734Y00473*
X02734Y00473*
X02732Y00488D02*
D01*
X02731Y00488*
X02731Y00488*
X0273Y00488*
X0273Y00488*
X02729Y00487*
X02729Y00487*
X02728Y00487*
X02728Y00487*
X02727Y00487*
X02727Y00486*
X02727Y00486*
X02726Y00485*
X02726Y00485*
X02725Y00485*
X02725Y00484*
X02725Y00484*
X02725Y00483*
X02725Y00483*
X02724Y00482*
X02724Y00482*
X02724Y00481*
X02724Y00481*
Y0048*
X02724Y0048*
X02724Y00479*
X02724Y00479*
X02725Y00478*
X02725Y00478*
X02725Y00477*
X02725Y00477*
X02725Y00476*
X02726Y00476*
X02726Y00475*
X02727Y00475*
X02727Y00475*
X02727Y00474*
X02728Y00474*
X02728Y00474*
X02729Y00474*
X02729Y00473*
X0273Y00473*
X0273Y00473*
X02731Y00473*
X02731Y00473*
X02732Y00473*
X02734Y00488D02*
D01*
X02734Y00488*
X02735Y00488*
X02735Y00488*
X02736Y00488*
X02736Y00488*
X02737Y00489*
X02737Y00489*
X02738Y00489*
X02738Y00489*
X02738Y0049*
X02739Y0049*
X02739Y0049*
X02739Y00491*
X0274Y00491*
X0274Y00492*
X0274Y00492*
X02741Y00493*
X02741Y00493*
X02741Y00494*
X02741Y00494*
X02741Y00495*
X02741Y00495*
Y00496*
X02741Y00496*
X02741Y00497*
X02741Y00497*
X02741Y00498*
X02741Y00498*
X0274Y00499*
X0274Y00499*
X0274Y005*
X02739Y005*
X02739Y005*
X02739Y00501*
X02738Y00501*
X02738Y00502*
X02738Y00502*
X02737Y00502*
X02737Y00502*
X02736Y00502*
X02736Y00503*
X02735Y00503*
X02735Y00503*
X02734Y00503*
X02734Y00503*
X02731Y00518D02*
D01*
X0273Y00518*
X0273Y00518*
X02729Y00518*
X02728Y00518*
X02728Y00517*
X02727Y00517*
X02727Y00517*
X02727Y00517*
X02726Y00517*
X02726Y00516*
X02725Y00516*
X02725Y00515*
X02725Y00515*
X02724Y00515*
X02724Y00514*
X02724Y00514*
X02724Y00513*
X02723Y00513*
X02723Y00512*
X02723Y00512*
X02723Y00511*
X02723Y00511*
Y0051*
X02723Y0051*
X02723Y00509*
X02723Y00509*
X02723Y00508*
X02724Y00508*
X02724Y00507*
X02724Y00507*
X02724Y00506*
X02725Y00506*
X02725Y00505*
X02725Y00505*
X02726Y00505*
X02726Y00504*
X02727Y00504*
X02727Y00504*
X02727Y00504*
X02728Y00503*
X02728Y00503*
X02729Y00503*
X0273Y00503*
X0273Y00503*
X02731Y00503*
X02733Y00518D02*
D01*
X02733Y00518*
X02734Y00518*
X02734Y00518*
X02735Y00518*
X02735Y00518*
X02736Y00519*
X02736Y00519*
X02737Y00519*
X02737Y00519*
X02737Y0052*
X02738Y0052*
X02738Y0052*
X02738Y00521*
X02739Y00521*
X02739Y00522*
X02739Y00522*
X0274Y00523*
X0274Y00523*
X0274Y00524*
X0274Y00524*
X0274Y00525*
X0274Y00525*
X0274Y00525*
X02704Y00405D02*
D01*
X02705Y00404*
X02706Y00403*
X02708Y00402*
X02709Y00402*
X0271Y00401*
X02711Y004*
X02713Y004*
X02714Y004*
X02716Y00399*
X02717Y00399*
X02718Y00399*
X0272Y00399*
X02721Y00399*
X02723Y004*
X02724Y004*
X02725Y004*
X02727Y00401*
X02728Y00401*
X02729Y00402*
X0273Y00403*
X02732Y00404*
X02733Y00405*
X02734Y00406*
X02409Y00366D02*
D01*
X02409Y00365*
X0241Y00365*
X0241Y00365*
X02411Y00364*
X02411Y00364*
X02419Y00362D02*
D01*
X02419Y00362*
X0242Y00362*
X0242Y00362*
X02421Y00362*
X02421Y00362*
X02422Y00362*
X02422Y00362*
X02423Y00362*
X02423Y00362*
X02424Y00363*
X02424Y00363*
X02425Y00363*
X02425Y00363*
X02425Y00364*
X02426Y00364*
X02426Y00365*
X02427Y00365*
X02427Y00365*
X02427Y00366*
X02427Y00366*
X02428Y00367*
X02428Y00367*
X02428Y00368*
X02428Y00368*
X02428Y00369*
X02428Y00369*
X02428Y00369*
X02443Y00372D02*
D01*
X02443Y00372*
X02443Y00373*
X02443Y00373*
X02443Y00374*
X02443Y00374*
X02442Y00375*
X02442Y00375*
X02442Y00376*
X02442Y00376*
X02441Y00377*
X02441Y00377*
X02441Y00377*
X0244Y00378*
X0244Y00378*
X02439Y00378*
X02439Y00378*
X02438Y00379*
X02438Y00379*
X02437Y00379*
X02437Y00379*
X02436Y00379*
X02436Y00379*
X02435*
X02435Y00379*
X02434Y00379*
X02434Y00379*
X02433Y00379*
X02433Y00379*
X02432Y00378*
X02432Y00378*
X02431Y00378*
X02431Y00378*
X02431Y00377*
X0243Y00377*
X0243Y00377*
X02429Y00376*
X02429Y00376*
X02429Y00375*
X02429Y00375*
X02429Y00374*
X02428Y00374*
X02428Y00373*
X02428Y00373*
X02428Y00372*
X02428Y00372*
X02443Y00361D02*
D01*
X02443Y00361*
X02443Y0036*
X02443Y0036*
X02443Y00359*
X02444Y00359*
X02444Y00358*
X02444Y00358*
X02444Y00357*
X02444Y00357*
X02445Y00356*
X02445Y00356*
X02446Y00356*
X02446Y00355*
X02446Y00355*
X02447Y00355*
X02447Y00355*
X02448Y00354*
X02448Y00354*
X02449Y00354*
X02397Y00376D02*
D01*
X02401Y00372*
X02405Y00369*
X02409Y00366*
X02409Y00366*
X02444Y00505D02*
D01*
X02444Y00505*
X02444Y00504*
X02445Y00504*
X02445Y00503*
X02445Y00503*
X02445Y00502*
X02445Y00502*
X02446Y00501*
X02446Y00501*
X02446Y005*
X02446Y005*
X02447Y005*
X02447Y00499*
X02448Y00499*
X02448Y00499*
X02449Y00498*
X02449Y00498*
X0245Y00498*
X0245Y00498*
X02451Y00498*
X02451Y00498*
X02452Y00498*
X02452Y00498*
X02456Y00483D02*
D01*
X02457Y00483*
X02457Y00483*
X02458Y00483*
X02458Y00483*
X02459Y00483*
X02459Y00483*
X0246Y00484*
X0246Y00484*
X02461Y00484*
X02461Y00484*
X02461Y00485*
X02462Y00485*
X02462Y00486*
X02462Y00486*
X02463Y00486*
X02463Y00487*
X02463Y00487*
X02463Y00488*
X02463Y00488*
X02464Y00489*
X02464Y00489*
X02464Y0049*
Y0049*
X02464Y00491*
X02464Y00491*
X02463Y00492*
X02463Y00492*
X02463Y00493*
X02463Y00493*
X02463Y00494*
X02462Y00494*
X02462Y00495*
X02462Y00495*
X02461Y00496*
X02461Y00496*
X02461Y00496*
X0246Y00497*
X0246Y00497*
X02459Y00497*
X02459Y00497*
X02458Y00497*
X02458Y00497*
X02457Y00498*
X02457Y00498*
X02456Y00498*
X02442Y00483D02*
D01*
X02442Y00483*
X02441Y00483*
X02441Y00482*
X0244Y00482*
X0244Y00482*
X02439Y00482*
X02439Y00482*
X02438Y00482*
X02438Y00481*
X02437Y00481*
X02437Y00481*
X02437Y0048*
X02436Y0048*
X02436Y00479*
X02436Y00479*
X02435Y00478*
X02435Y00478*
X02435Y00477*
X02435Y00477*
X02435Y00476*
X02435Y00476*
X02435Y00475*
Y00475*
X02435Y00474*
X02435Y00474*
X02435Y00473*
X02435Y00473*
X02435Y00472*
X02435Y00472*
X02436Y00471*
X02436Y00471*
X02436Y00471*
X02437Y0047*
X02437Y0047*
X02437Y00469*
X02438Y00469*
X02438Y00469*
X02439Y00469*
X02439Y00468*
X0244Y00468*
X0244Y00468*
X02441Y00468*
X02441Y00468*
X02442Y00468*
X02442Y00468*
X02458Y00453D02*
D01*
X02459Y00453*
X02459Y00453*
X0246Y00453*
X0246Y00453*
X02461Y00453*
X02461Y00453*
X02462Y00454*
X02462Y00454*
X02463Y00454*
X02463Y00454*
X02464Y00455*
X02464Y00455*
X02464Y00456*
X02465Y00456*
X02465Y00456*
X02465Y00457*
X02465Y00457*
X02465Y00458*
X02466Y00458*
X02466Y00459*
X02466Y00459*
X02466Y0046*
Y0046*
X02466Y00461*
X02466Y00461*
X02466Y00462*
X02465Y00462*
X02465Y00463*
X02465Y00463*
X02465Y00464*
X02465Y00464*
X02464Y00465*
X02464Y00465*
X02464Y00466*
X02463Y00466*
X02463Y00466*
X02462Y00467*
X02462Y00467*
X02461Y00467*
X02461Y00467*
X0246Y00467*
X0246Y00467*
X02459Y00468*
X02459Y00468*
X02458Y00468*
X02452Y00453D02*
D01*
X02451Y00453*
X02451Y00453*
X0245Y00452*
X0245Y00452*
X02449Y00452*
X02449Y00452*
X02448Y00452*
X02448Y00452*
X02447Y00451*
X02447Y00451*
X02447Y00451*
X02446Y0045*
X02446Y0045*
X02446Y00449*
X02445Y00449*
X02445Y00448*
X02445Y00448*
X02445Y00447*
X02445Y00447*
X02444Y00446*
X02444Y00446*
X02444Y00445*
X02444Y00445*
Y00423D02*
D01*
X02444Y00423*
X02444Y00423*
X02444Y00422*
X02445Y00422*
X02445Y00421*
X02445Y00421*
X02445Y00421*
X02445Y0042*
X02445Y0042*
X02446Y0042*
X02446Y0042*
X02446Y00419*
X02446Y00419*
X02474Y00722D02*
D01*
X02469Y00717*
X02465Y00711*
X02461Y00706*
X02457Y007*
X02454Y00693*
X02451Y00687*
X02449Y0068*
X02447Y00674*
X02446Y00667*
X02445Y0066*
X02444Y00653*
X02444Y00651*
X02453Y00414D02*
D01*
X02453Y00414*
X02453Y00414*
X02453Y00414*
X02453Y00414*
X02453Y00414*
X02453Y00414D02*
D01*
X02454Y00413*
X02455Y00412*
X02456Y00412*
X02457Y00411*
X02458Y00411*
X02459Y0041*
X0246Y0041*
X02461Y0041*
X02463Y0041*
X02464Y0041*
X02465Y0041*
X02466Y0041*
X02467Y0041*
X02468Y0041*
X02469Y0041*
X02881Y00482D02*
D01*
X02882Y00482*
X02882Y00482*
X02882Y00482*
X02882Y00483*
X02882Y00483*
X02883Y00483*
X02883Y00484*
X02883Y00484*
X02883Y00484*
X02883Y00485*
X02883Y00485*
X02883Y00485*
X02872Y0077D02*
D01*
X02872Y00772*
X02872Y00775*
X02871Y00777*
X02871Y0078*
X0287Y00782*
X02869Y00784*
X02868Y00786*
X02867Y00789*
X02865Y00791*
X02864Y00793*
X02862Y00794*
X02862Y00795*
X02849Y00403D02*
D01*
X02849Y00403*
X0285Y00403*
X0285Y00403*
X02851Y00403*
X02851Y00403*
X02852Y00404*
X02852Y00404*
X02853Y00404*
X02853Y00404*
X02853Y00405*
X02854Y00405*
X02854Y00405*
X02848Y00403D02*
D01*
X02847Y00403*
X02847Y00403*
X02846Y00403*
X02846Y00403*
X02846Y00403*
X02845Y00402*
X02845Y00402*
X02844Y00402*
X02844Y00402*
X02844Y00402*
X02843Y00401*
X02843Y00401*
D01*
X02843Y00401*
X02843Y00401*
X02843Y004*
X02842Y004*
X02842Y004*
X02842Y00399*
X02842Y00399*
X02842Y00398*
X02842Y00398*
X02842Y00398*
X02842Y00397*
X02842Y00397*
X0284Y00393D02*
D01*
X0284Y00393*
X0284Y00393*
X02841Y00393*
X02841Y00394*
X02841Y00394*
X02841Y00394*
X02841Y00395*
X02841Y00395*
X02842Y00395*
X02842Y00396*
X02842Y00396*
X02842Y00396*
X02735Y00392D02*
D01*
X02737Y00393*
X02739Y00395*
X0274Y00396*
X02742Y00398*
X02744Y004*
X02745Y00402*
X02746Y00404*
X02748Y00407*
X02749Y00409*
X02749Y00411*
X0275Y00414*
X02751Y00416*
X02751Y00418*
X02751Y00421*
X02751Y00422*
X02671Y00399D02*
D01*
X02674Y00396*
X02676Y00394*
X02679Y00392*
X02682Y0039*
X02686Y00389*
X02689Y00387*
X02692Y00386*
X02696Y00385*
X02699Y00384*
X02703Y00384*
X02706Y00384*
X0271Y00384*
X02713Y00384*
X02717Y00385*
X0272Y00386*
X02724Y00387*
X02727Y00388*
X0273Y00389*
X02733Y00391*
X02735Y00392*
X02759Y00795D02*
D01*
X02758Y00793*
X02757Y00792*
X02756Y0079*
X02755Y00788*
X02754Y00787*
X02753Y00785*
X02752Y00783*
X02752Y00781*
X02751Y00779*
X02751Y00777*
X02751Y00775*
X02751Y00775*
X02823Y00973D02*
D01*
X02822Y00972*
X02822Y00971*
X02821Y0097*
X0282Y00969*
X0282Y00968*
X02819Y00966*
X02819Y00965*
X02818Y00964*
X02818Y00963*
X02818Y00962*
X02818Y0096*
X02818Y0096*
X02893Y00795D02*
D01*
X02892Y00793*
X0289Y00791*
X02889Y00789*
X02887Y00787*
X02886Y00785*
X02885Y00783*
X02884Y0078*
X02884Y00778*
X02883Y00776*
X02883Y00773*
X02883Y00771*
X02883Y0077*
X0274Y00775D02*
D01*
X0274Y00777*
X0274Y00779*
X02739Y00781*
X02739Y00782*
X02738Y00784*
X02738Y00786*
X02737Y00788*
X02736Y0079*
X02735Y00791*
X02733Y00793*
X02732Y00794*
X02732Y00795*
X0235Y00405D02*
D01*
X0235Y00405*
X0235Y00405*
X0235Y00405*
X0235Y00405*
X02351Y00405*
X02351Y00404*
X02351Y00404*
X02351Y00404*
X02351Y00404*
X02351Y00404*
X02351Y00404*
X02352Y00404*
X02363Y00403D02*
D01*
X02362Y00403*
X02362Y00403*
X02362Y00404*
X02361Y00404*
X02361Y00404*
X02361Y00404*
X02361Y00404*
X0236Y00404*
X0236Y00404*
X0236Y00404*
X02359Y00404*
X02359Y00404*
X02364Y00399D02*
D01*
X02364Y004*
X02364Y004*
X02364Y004*
X02364Y00401*
X02364Y00401*
X02364Y00401*
X02363Y00402*
X02363Y00402*
X02363Y00402*
X02363Y00403*
X02363Y00403*
X02363Y00403*
X02364Y00397D02*
D01*
X02364Y00396*
X02364Y00396*
X02364Y00395*
X02364Y00394*
X02365Y00393*
X02365Y00393*
X02365Y00392*
X02366Y00392*
X02366Y00391*
X02367Y0039*
X02367Y0039*
X02367Y0039*
X02389Y00368D02*
D01*
X02393Y00364*
X02398Y0036*
X02403Y00357*
X02408Y00353*
X02413Y00351*
X02419Y00348*
X02424Y00347*
X0243Y00345*
X02436Y00344*
X02442Y00343*
X02448Y00343*
X02449Y00343*
X02535D02*
D01*
X02536Y00343*
X02536Y00343*
X02537Y00343*
X02538Y00343*
X02539Y00343*
X02539Y00344*
X0254Y00344*
X02541Y00344*
X02541Y00345*
X02542Y00345*
X02543Y00346*
X02543Y00346*
X02585Y00388D02*
D01*
X0259Y00394*
X02595Y004*
X02599Y00406*
X02603Y00413*
X02607Y0042*
X0261Y00427*
X02612Y00434*
X02614Y00442*
X02616Y00449*
X02617Y00457*
X02617Y00465*
X02617Y00466*
X02625Y00795D02*
D01*
X02624Y00793*
X02623Y00792*
X02622Y0079*
X02621Y00788*
X0262Y00787*
X02619Y00785*
X02618Y00783*
X02618Y00781*
X02618Y00779*
X02617Y00777*
X02617Y00775*
X02617Y00775*
X02388Y00404D02*
D01*
X02388Y00404*
X02388Y00404*
X02388Y00404*
X02388Y00404*
X02388Y00404*
X02389Y00405*
X02389Y00405*
X02389Y00405*
X02389Y00405*
X02389Y00405*
X02389Y00405*
X02389Y00405*
X0238Y00404D02*
D01*
X0238Y00404*
X02379Y00404*
X02379Y00404*
X02379Y00404*
X02378Y00404*
X02378Y00404*
X02378Y00404*
X02377Y00404*
X02377Y00403*
X02377Y00403*
X02377Y00403*
X02377Y00403*
D01*
X02376Y00403*
X02376Y00402*
X02376Y00402*
X02376Y00402*
X02376Y00401*
X02375Y00401*
X02375Y00401*
X02375Y004*
X02375Y004*
X02375Y004*
X02375Y00399*
X02375Y00399*
D01*
X02375Y00399*
X02375Y00399*
X02375Y00398*
X02375Y00398*
X02375Y00398*
X02376Y00397*
X02376Y00397*
X02376Y00397*
X02376Y00396*
X02376Y00396*
X02376Y00396*
X02377Y00396*
X02577D02*
D01*
X02582Y00401*
X02586Y00406*
X0259Y00412*
X02594Y00418*
X02597Y00424*
X026Y00431*
X02602Y00437*
X02604Y00444*
X02605Y00451*
X02606Y00458*
X02606Y00465*
X02606Y00467*
Y00775D02*
D01*
X02606Y00777*
X02606Y00779*
X02606Y00781*
X02605Y00782*
X02604Y00784*
X02604Y00786*
X02603Y00788*
X02602Y0079*
X02601Y00791*
X026Y00793*
X02598Y00794*
X02598Y00795*
X02818Y0096D02*
D01*
X02818Y00959*
X02818Y00958*
X02818Y00956*
X02819Y00955*
X02819Y00954*
X0282Y00953*
X0282Y00952*
X02821Y00951*
X02821Y0095*
X02822Y00949*
X02823Y00948*
X02823Y00947*
X02925Y00789D02*
D01*
X02924Y00796*
X02924Y00803*
X02923Y0081*
X02921Y00817*
X02919Y00823*
X02916Y0083*
X02913Y00836*
X0291Y00842*
X02906Y00848*
X02901Y00853*
X02897Y00858*
X02895Y0086*
X02807Y00958D02*
D01*
X02807Y00956*
X02807Y00955*
X02808Y00953*
X02808Y00951*
X02808Y0095*
X02809Y00948*
X0281Y00947*
X02811Y00945*
X02811Y00944*
X02812Y00943*
X02814Y00942*
X02814Y00941*
X02807Y00958D02*
D01*
X02807Y00959*
X02807Y00961*
X02806Y00963*
X02806Y00964*
X02806Y00966*
X02805Y00967*
X02804Y00969*
X02803Y0097*
X02803Y00972*
X02802Y00973*
X028Y00974*
X028Y00974*
X02936Y00808D02*
D01*
X02936Y00813*
X02935Y00817*
X02934Y00822*
X02933Y00826*
X02932Y0083*
X0293Y00834*
X02928Y00839*
X02926Y00842*
X02923Y00846*
X02921Y0085*
X02918Y00853*
X02917Y00854*
X02689Y0096D02*
D01*
X02689Y00961*
X02689Y00963*
X02688Y00964*
X02688Y00965*
X02688Y00966*
X02687Y00967*
X02687Y00968*
X02686Y0097*
X02685Y00971*
X02685Y00972*
X02684Y00972*
X02684Y00973*
Y00947D02*
D01*
X02684Y00948*
X02685Y00949*
X02686Y0095*
X02687Y00951*
X02687Y00953*
X02688Y00954*
X02688Y00955*
X02688Y00956*
X02689Y00957*
X02689Y00958*
X02689Y0096*
X02689Y0096*
X02707Y00974D02*
D01*
X02706Y00973*
X02705Y00972*
X02704Y0097*
X02703Y00969*
X02702Y00968*
X02701Y00966*
X02701Y00965*
X027Y00963*
X027Y00961*
X027Y0096*
X027Y00958*
X027Y00958*
X02693Y00941D02*
D01*
X02694Y00942*
X02695Y00944*
X02696Y00945*
X02697Y00946*
X02698Y00948*
X02698Y00949*
X02699Y00951*
X02699Y00953*
X027Y00954*
X027Y00956*
X027Y00957*
X027Y00958*
X02478Y0039D02*
X02496D01*
X02478D02*
X02478D01*
X02425Y0063D02*
Y00436D01*
X02471Y0039D02*
X02478D01*
X02984Y00391D02*
D01*
X02953Y00399D02*
X02953Y00399D01*
X02983Y0039D02*
D01*
X02925Y0047D02*
Y00789D01*
X02953Y00399D02*
D01*
X02936Y00498D02*
Y00808D01*
X02938Y00493D02*
D01*
X0298Y00409D02*
D01*
X02962Y00424D02*
X02975Y00412D01*
X02959Y00433D02*
X02962Y00424D01*
X02959Y00433D02*
D01*
X02966Y00443D02*
D01*
X02945Y00458D02*
X02966D01*
X02945Y00473D02*
X02955D01*
X02945Y00488D02*
X02955D01*
X02937Y00495D02*
X02938Y00493D01*
X02936Y00498D02*
X02937Y00495D01*
X02818Y00406D02*
X02819Y00407D01*
X02816Y00412D02*
X02816Y00411D01*
X02816Y00412D02*
X02817Y00417D01*
X02836Y00436*
X02847D02*
X02851Y00432D01*
X02856Y00449D02*
X02862Y00443D01*
X02866Y0046D02*
X02872Y00454D01*
X02879Y00468D02*
X02883Y00464D01*
X02879Y00479D02*
D01*
X02881Y00481*
X02821Y00407D02*
X02821D01*
X02821Y00407D02*
X02821Y00407D01*
X02803Y00407D02*
Y00407D01*
X02811Y0043D02*
X0287Y00489D01*
X02811Y0043D02*
X02811Y0043D01*
X02809Y00393D02*
X02809Y00393D01*
X02819Y00407D02*
X02821D01*
X02816Y00411D02*
X02818Y00406D01*
X02872Y00492D02*
Y0077D01*
X02881Y00481D02*
X02881Y00482D01*
X02735Y00407D02*
X02735Y00407D01*
X02736Y00408D02*
X0274Y00423D01*
Y00435*
X02733Y00443D02*
D01*
Y00458D02*
X02734D01*
X02732Y00473D02*
X02734D01*
X02732Y00488D02*
X02734D01*
X02731Y00503D02*
X02734D01*
X02731Y00518D02*
X02733D01*
X0274Y00525D02*
Y00543D01*
Y00775*
X02411Y00364D02*
X02419Y00362D01*
D01*
X02428Y00369D02*
Y00372D01*
X02443Y00361D02*
Y00372D01*
X02449Y00354D02*
D01*
X02449Y00354*
X0246*
X02468*
X02535*
X02444Y00505D02*
Y00562D01*
X02452Y00498D02*
X02456D01*
X02442Y00483D02*
X02456D01*
X02442Y00468D02*
X02458D01*
X02452Y00453D02*
X02458D01*
X02444Y00428D02*
Y00445D01*
Y00562D02*
Y00651D01*
Y00423D02*
Y00428D01*
X02446Y00419D02*
X02453Y00414D01*
X02883Y00509D02*
Y0077D01*
X02751Y00422D02*
Y00775D01*
X02449Y00343D02*
X02535D01*
X02617Y00466D02*
Y00775D01*
X02606Y00467D02*
Y00775D01*
X02476Y0074D02*
X02684Y00947D01*
X02484Y00732D02*
X02693Y00941D01*
X02453Y00414D02*
X02453Y00414D01*
X02466Y0073D02*
X02466Y0073D01*
X02469Y0041D02*
X02469Y0041D01*
X02469Y0041*
X02883Y00485D02*
Y00509D01*
X02893Y00795D02*
Y00795D01*
X02848Y00403D02*
X02849D01*
X02842Y00396D02*
Y00397D01*
X02665Y00405D02*
X02671Y00399D01*
D01*
X02751Y00422D02*
Y00422D01*
X02704Y00405D02*
D01*
X02814Y00941D02*
X02895Y0086D01*
X02466Y0073D02*
X02476Y0074D01*
X02474Y00722D02*
X02484Y00732D01*
X02759Y00795D02*
Y00795D01*
Y00795D02*
D01*
X02732D02*
Y00795D01*
X02352Y00404D02*
X02359D01*
X02364Y00397D02*
Y00399D01*
X02543Y00346D02*
X02585Y00388D01*
X02625Y00795D02*
D01*
Y00795D01*
Y00795D02*
D01*
X0238Y00404D02*
X02388D01*
X02375Y00399D02*
D01*
X02377Y00396D02*
X02397Y00376D01*
X02535Y00354D02*
X02577Y00396D01*
X02598Y00795D02*
Y00795D01*
X02367Y0039D02*
X02389Y00368D01*
X02823Y00973D02*
X02826Y00976D01*
X02799D02*
X028Y00974D01*
X02823Y00947D02*
X02917Y00854D01*
X02826Y00976D02*
Y00976D01*
X02799Y00976D02*
Y00976D01*
X02689Y0096D02*
D01*
X02681Y00976D02*
X02684Y00973D01*
X02707Y00974D02*
X02708Y00976D01*
X02681D02*
Y00976D01*
X02708Y00976D02*
Y00976D01*
G54D153*
X01849Y00271D02*
Y03701D01*
G54D158*
X04327Y02307D03*
G54D160*
X05578Y0089D03*
Y02489D03*
X04062Y02595D03*
G54D168*
X02043Y04257D03*
X01457Y04253D03*
G54D171*
X02494Y02661D03*
X02692Y02721D03*
X02511Y00405D03*
X0298Y00409D03*
X02821Y00407D03*
X02469Y0041D03*
X02854Y00405D03*
X02665D03*
X02704D03*
X0235D03*
X02389D03*
X03019D03*
X02732Y00795D03*
X02681Y00976D03*
X02708D03*
X02625Y00795D03*
X02598D03*
X02826Y00976D03*
X02799D03*
X02759Y00795D03*
X02862D03*
X02893D03*
X02475Y02291D03*
X03894Y01566D03*
X01754Y02126D03*
X03197Y01714D03*
X03439Y0187D03*
X03298Y01971D03*
X02985Y02287D03*
X02702Y02289D03*
X02272Y02463D03*
X01719Y01536D03*
X02942Y02286D03*
X01568Y02067D03*
X03773Y01666D03*
X02599Y02436D03*
X02894Y02431D03*
X02579Y02281D03*
X01619Y02121D03*
X02726Y02293D03*
X01884Y02071D03*
X0292Y02428D03*
X0245Y02282D03*
X03252Y01661D03*
X03392Y01871D03*
X02409Y02283D03*
X03549Y01441D03*
X02624Y02461D03*
X03834Y01481D03*
X03864Y01511D03*
X03924Y01536D03*
X03329Y01826D03*
X02645Y02274D03*
X02665Y02291D03*
X03803Y01691D03*
X03224Y01661D03*
X02252Y02613D03*
X01393Y01816D03*
X0099Y00687D03*
X03197Y0297D03*
X03491Y03103D03*
X0323Y03235D03*
X03358Y03448D03*
X03068Y03395D03*
X03056Y01811D03*
X02254Y03536D03*
X02579Y03486D03*
X02389Y03481D03*
X02434Y03546D03*
X02634Y03406D03*
X02004Y01336D03*
X02028Y01361D03*
X02549Y01755D03*
X02462Y03172D03*
X02146Y04103D03*
X02253Y04086D03*
X01345Y04175D03*
X04039Y02406D03*
X03263Y03303D03*
X01852Y00255D03*
X01832Y00287D03*
X01852D03*
X02231Y02584D03*
X05577Y02214D03*
X02694Y01481D03*
X02384Y01941D03*
X03744Y03261D03*
X05634Y02236D03*
X02626Y0177D03*
X03939Y03121D03*
X02604Y01734D03*
X02299Y01916D03*
X02579Y0179D03*
X02259Y03261D03*
X03374Y03273D03*
X03368Y0305D03*
X03806Y03235D03*
X01459Y03147D03*
X0144Y03557D03*
X03623Y02587D03*
X03622Y03486D03*
X03491Y03297D03*
X03542Y03319D03*
X03344Y02996D03*
X03653Y03293D03*
X03394Y03447D03*
X03436Y03457D03*
X03589Y01711D03*
X02478Y00937D03*
X02206Y01298D03*
X02205Y032D03*
X02502Y01316D03*
X02525Y02463D03*
X03342Y02263D03*
X03498Y02341D03*
X02429Y02621D03*
X02446Y01437D03*
X02409Y01967D03*
X02643Y01616D03*
X02666Y0164D03*
X01884Y03601D03*
X01754Y03661D03*
X01549Y03621D03*
X01574Y03596D03*
X02084Y03896D03*
X02083Y01411D03*
X02059Y01386D03*
Y03871D03*
X02029Y03836D03*
X02004Y03816D03*
X02234Y03506D03*
X02993Y03751D03*
X03014Y03831D03*
X02894Y01561D03*
X02919Y01536D03*
X02274Y01506D03*
X02719Y01591D03*
X03724Y01675D03*
X01779Y04156D03*
X03504Y04086D03*
X03854Y03151D03*
X03829Y03176D03*
X03799Y03201D03*
X03302Y03344D03*
X03469Y03456D03*
X01849Y03701D03*
M02*